(kicad_pcb
	(version 20240108)
	(generator "pcbnew")
	(generator_version "8.0")
	(general
		(thickness 1.62)
		(legacy_teardrops no)
	)
	(paper "A4")
	(title_block
		(title "Jetson Orin Baseboard")
		(date "2025-03-12")
		(rev "1.3.4")
		(company "Antmicro Ltd")
		(comment 1 "www.antmicro.com")
		(comment 9 "footprints 389-392 of 677")
	)
	(layers
		(0 "F.Cu" signal)
		(1 "In1.Cu" signal)
		(2 "In2.Cu" signal)
		(3 "In3.Cu" signal)
		(4 "In4.Cu" jumper)
		(5 "In5.Cu" signal)
		(6 "In6.Cu" signal)
		(31 "B.Cu" signal)
		(32 "B.Adhes" user "B.Adhesive")
		(33 "F.Adhes" user "F.Adhesive")
		(34 "B.Paste" user)
		(35 "F.Paste" user)
		(36 "B.SilkS" user "B.Silkscreen")
		(37 "F.SilkS" user "F.Silkscreen")
		(38 "B.Mask" user)
		(39 "F.Mask" user)
		(40 "Dwgs.User" user "User.Drawings")
		(41 "Cmts.User" user "User.Comments")
		(42 "Eco1.User" user "User.Eco1")
		(43 "Eco2.User" user "User.Eco2")
		(44 "Edge.Cuts" user)
		(45 "Margin" user)
		(46 "B.CrtYd" user "B.Courtyard")
		(47 "F.CrtYd" user "F.Courtyard")
		(48 "B.Fab" user)
		(49 "F.Fab" user)
	)
	(footprint "antmicro-footprints:XSON-8_1x1.95mm_P0.5mm"
		(layer "B.Cu")
		(at 68.1 85.8)
		(property "Reference" "U32"
			(at 1.12 2.26 180)
			(layer "B.SilkS")
			(effects
				(font
					(size 0.7 0.7)
					(thickness 0.15)
				)
				(justify left bottom mirror)
			)
		)
		(property "Value" "NTS0102_XSON"
			(at 0 -2.2 180)
			(layer "B.Fab")
			(effects
				(font
					(size 0.7 0.7)
					(thickness 0.15)
				)
				(justify left bottom mirror)
			)
		)
		(property "Footprint" "antmicro-footprints:XSON-8_1x1.95mm_P0.5mm"
			(at 0 0 0)
			(layer "F.Fab")
			(hide yes)
			(effects
				(font
					(size 1.27 1.27)
					(thickness 0.15)
				)
			)
		)
		(property "Datasheet" "http://www.farnell.com/datasheets/1760723.pdf"
			(at 0 0 0)
			(layer "F.Fab")
			(hide yes)
			(effects
				(font
					(size 1.27 1.27)
					(thickness 0.15)
				)
			)
		)
		(property "Author" "Antmicro"
			(at 0 0 0)
			(layer "B.Fab")
			(hide yes)
			(effects
				(font
					(size 1 1)
					(thickness 0.15)
				)
				(justify mirror)
			)
		)
		(property "License" "Apache-2.0"
			(at 0 0 0)
			(layer "B.Fab")
			(hide yes)
			(effects
				(font
					(size 1 1)
					(thickness 0.15)
				)
				(justify mirror)
			)
		)
		(property "MPN" "NTS0102GT"
			(at 0 0 0)
			(layer "B.Fab")
			(hide yes)
			(effects
				(font
					(size 1 1)
					(thickness 0.15)
				)
				(justify mirror)
			)
		)
		(property "Manufacturer" "NXP"
			(at 0 0 0)
			(layer "B.Fab")
			(hide yes)
			(effects
				(font
					(size 1 1)
					(thickness 0.15)
				)
				(justify mirror)
			)
		)
		(sheetname "CSI")
		(sheetfile "csi.kicad_sch")
		(attr smd)
		(fp_line
			(start -0.5 -1.1)
			(end 0.5 -1.1)
			(stroke
				(width 0.15)
				(type solid)
			)
			(layer "B.SilkS")
		)
		(fp_line
			(start 0.5 1.1)
			(end -0.5 1.1)
			(stroke
				(width 0.15)
				(type solid)
			)
			(layer "B.SilkS")
		)
		(fp_circle
			(center -0.75 1.1)
			(end -0.701 1.1)
			(stroke
				(width 0.15)
				(type solid)
			)
			(fill none)
			(layer "B.SilkS")
		)
		(fp_rect
			(start -0.8 1.2)
			(end 0.8 -1.2)
			(stroke
				(width 0.05)
				(type solid)
			)
			(fill none)
			(layer "B.CrtYd")
		)
		(fp_line
			(start -0.5305 -1)
			(end 0.5305 -1)
			(stroke
				(width 0.15)
				(type solid)
			)
			(layer "B.Fab")
		)
		(fp_line
			(start -0.5305 1.001)
			(end -0.5305 -1)
			(stroke
				(width 0.15)
				(type solid)
			)
			(layer "B.Fab")
		)
		(fp_line
			(start 0.5305 -1)
			(end 0.5305 1.001)
			(stroke
				(width 0.15)
				(type solid)
			)
			(layer "B.Fab")
		)
		(fp_line
			(start 0.5305 1.001)
			(end -0.5305 1.001)
			(stroke
				(width 0.15)
				(type solid)
			)
			(layer "B.Fab")
		)
		(fp_text user "License: Apache-2.0"
			(at -0.527 -8.306 180)
			(layer "B.Fab")
			(hide yes)
			(effects
				(font
					(size 0.7 0.7)
					(thickness 0.15)
				)
				(justify left bottom mirror)
			)
		)
		(fp_text user "${REFERENCE}"
			(at -0.527 -5.905 180)
			(layer "B.Fab")
			(hide yes)
			(effects
				(font
					(size 0.7 0.7)
					(thickness 0.15)
				)
				(justify left bottom mirror)
			)
		)
		(fp_text user "Author: Antmicro"
			(at -0.527 -7.105 180)
			(layer "B.Fab")
			(hide yes)
			(effects
				(font
					(size 0.7 0.7)
					(thickness 0.15)
				)
				(justify left bottom mirror)
			)
		)
		(pad "1" smd roundrect
			(at -0.45 0.75 180)
			(size 0.6 0.3)
			(layers "B.Cu" "B.Paste" "B.Mask")
			(roundrect_rratio 0.25)
			(net 402 "/CSI/VSYNC_CAM3_3V3")
			(pinfunction "B_{2}")
			(pintype "bidirectional")
		)
		(pad "2" smd roundrect
			(at -0.45 0.25 180)
			(size 0.6 0.25)
			(layers "B.Cu" "B.Paste" "B.Mask")
			(roundrect_rratio 0.25)
			(net 1 "GND")
			(pinfunction "GND")
			(pintype "power_in")
		)
		(pad "3" smd roundrect
			(at -0.45 -0.25 180)
			(size 0.6 0.25)
			(layers "B.Cu" "B.Paste" "B.Mask")
			(roundrect_rratio 0.25)
			(net 112 "+1V8")
			(pinfunction "VCC_{A}")
			(pintype "power_in")
		)
		(pad "4" smd roundrect
			(at -0.45 -0.75 180)
			(size 0.6 0.3)
			(layers "B.Cu" "B.Paste" "B.Mask")
			(roundrect_rratio 0.25)
			(net 243 "VSYNC_CAM3")
			(pinfunction "A_{2}")
			(pintype "bidirectional")
		)
		(pad "5" smd roundrect
			(at 0.45 -0.75 180)
			(size 0.6 0.3)
			(layers "B.Cu" "B.Paste" "B.Mask")
			(roundrect_rratio 0.25)
			(net 242 "VSYNC_CAM2")
			(pinfunction "A_{1}")
			(pintype "bidirectional")
		)
		(pad "6" smd roundrect
			(at 0.45 -0.25 180)
			(size 0.6 0.25)
			(layers "B.Cu" "B.Paste" "B.Mask")
			(roundrect_rratio 0.25)
			(net 112 "+1V8")
			(pinfunction "OE")
			(pintype "input")
		)
		(pad "7" smd roundrect
			(at 0.45 0.25 180)
			(size 0.6 0.25)
			(layers "B.Cu" "B.Paste" "B.Mask")
			(roundrect_rratio 0.25)
			(net 87 "+3V3")
			(pinfunction "VCC_{B}")
			(pintype "power_in")
		)
		(pad "8" smd roundrect
			(at 0.45 0.75 180)
			(size 0.6 0.3)
			(layers "B.Cu" "B.Paste" "B.Mask")
			(roundrect_rratio 0.25)
			(net 406 "/CSI/VSYNC_CAM2_3V3")
			(pinfunction "B_{1}")
			(pintype "bidirectional")
		)
	)
	(footprint "antmicro-footprints:R_0603_1608Metric"
		(layer "B.Cu")
		(at 62.8 82.7)
		(descr "Resistor SMD 0603")
		(tags "resistor SMD 0603")
		(property "Reference" "R276"
			(at 1.45 -0.6 180)
			(layer "B.SilkS")
			(effects
				(font
					(size 0.7 0.7)
					(thickness 0.15)
				)
				(justify left bottom mirror)
			)
		)
		(property "Value" "R_0R_0603"
			(at 0 -1.6 180)
			(layer "B.Fab")
			(effects
				(font
					(size 0.7 0.7)
					(thickness 0.15)
				)
				(justify left bottom mirror)
			)
		)
		(property "Footprint" "antmicro-footprints:R_0603_1608Metric"
			(at 0 0 0)
			(layer "F.Fab")
			(hide yes)
			(effects
				(font
					(size 1.27 1.27)
					(thickness 0.15)
				)
			)
		)
		(property "Datasheet" "https://www.bourns.com/docs/product-datasheets/cr.pdf?sfvrsn=574d41f6_14"
			(at 0 0 0)
			(layer "F.Fab")
			(hide yes)
			(effects
				(font
					(size 1.27 1.27)
					(thickness 0.15)
				)
			)
		)
		(property "Author" "Antmicro"
			(at 0 0 0)
			(layer "B.Fab")
			(hide yes)
			(effects
				(font
					(size 1 1)
					(thickness 0.15)
				)
				(justify mirror)
			)
		)
		(property "Current" "1A"
			(at 0 0 0)
			(layer "B.Fab")
			(hide yes)
			(effects
				(font
					(size 1 1)
					(thickness 0.15)
				)
				(justify mirror)
			)
		)
		(property "License" "Apache-2.0"
			(at 0 0 0)
			(layer "B.Fab")
			(hide yes)
			(effects
				(font
					(size 1 1)
					(thickness 0.15)
				)
				(justify mirror)
			)
		)
		(property "MPN" "CR0603-J/-000ELF"
			(at 0 0 0)
			(layer "B.Fab")
			(hide yes)
			(effects
				(font
					(size 1 1)
					(thickness 0.15)
				)
				(justify mirror)
			)
		)
		(property "Manufacturer" "Bourns"
			(at 0 0 0)
			(layer "B.Fab")
			(hide yes)
			(effects
				(font
					(size 1 1)
					(thickness 0.15)
				)
				(justify mirror)
			)
		)
		(property "Tolerance" ""
			(at 0 0 0)
			(layer "B.Fab")
			(hide yes)
			(effects
				(font
					(size 1 1)
					(thickness 0.15)
				)
				(justify mirror)
			)
		)
		(property "Val" "0R"
			(at 0 0 0)
			(layer "B.Fab")
			(hide yes)
			(effects
				(font
					(size 1 1)
					(thickness 0.15)
				)
				(justify mirror)
			)
		)
		(sheetname "Supply")
		(sheetfile "supply.kicad_sch")
		(attr smd)
		(fp_line
			(start 0.15 -0.4)
			(end -0.15 -0.4)
			(stroke
				(width 0.15)
				(type solid)
			)
			(layer "B.SilkS")
		)
		(fp_line
			(start 0.15 0.4)
			(end -0.15 0.4)
			(stroke
				(width 0.15)
				(type solid)
			)
			(layer "B.SilkS")
		)
		(fp_rect
			(start -1.25 0.65)
			(end 1.25 -0.65)
			(stroke
				(width 0.05)
				(type solid)
			)
			(fill none)
			(layer "B.CrtYd")
		)
		(fp_rect
			(start -0.8 0.4)
			(end 0.8 -0.4)
			(stroke
				(width 0.15)
				(type solid)
			)
			(fill none)
			(layer "B.Fab")
		)
		(fp_text user "Author: Antmicro"
			(at -1.25 -4.9 180)
			(layer "B.Fab")
			(hide yes)
			(effects
				(font
					(size 0.7 0.7)
					(thickness 0.15)
				)
				(justify left bottom mirror)
			)
		)
		(fp_text user "License: Apache-2.0"
			(at -1.25 -5.9 180)
			(layer "B.Fab")
			(hide yes)
			(effects
				(font
					(size 0.7 0.7)
					(thickness 0.15)
				)
				(justify left bottom mirror)
			)
		)
		(fp_text user "${REFERENCE}"
			(at -1.25 -3.898 180)
			(layer "B.Fab")
			(hide yes)
			(effects
				(font
					(size 0.7 0.7)
					(thickness 0.15)
				)
				(justify left bottom mirror)
			)
		)
		(pad "1" smd roundrect
			(at -0.7 0)
			(size 0.8 1)
			(layers "B.Cu" "B.Paste" "B.Mask")
			(roundrect_rratio 0.2)
			(net 139 "/Supply/1V8_LDO")
			(pintype "passive")
		)
		(pad "2" smd roundrect
			(at 0.7 0)
			(size 0.8 1)
			(layers "B.Cu" "B.Paste" "B.Mask")
			(roundrect_rratio 0.2)
			(net 112 "+1V8")
			(pintype "passive")
		)
	)
	(footprint "antmicro-footprints:XSON-8_1x1.95mm_P0.5mm"
		(layer "B.Cu")
		(at 49.78 111.3245 -90)
		(property "Reference" "U47"
			(at -1.2745 1.23 0)
			(layer "B.SilkS")
			(effects
				(font
					(size 0.7 0.7)
					(thickness 0.15)
				)
				(justify right bottom mirror)
			)
		)
		(property "Value" "NTS0102_XSON"
			(at 0 -2.2 90)
			(layer "B.Fab")
			(effects
				(font
					(size 0.7 0.7)
					(thickness 0.15)
				)
				(justify left bottom mirror)
			)
		)
		(property "Footprint" "antmicro-footprints:XSON-8_1x1.95mm_P0.5mm"
			(at 0 0 -90)
			(layer "F.Fab")
			(hide yes)
			(effects
				(font
					(size 1.27 1.27)
					(thickness 0.15)
				)
			)
		)
		(property "Datasheet" "http://www.farnell.com/datasheets/1760723.pdf"
			(at 0 0 -90)
			(layer "F.Fab")
			(hide yes)
			(effects
				(font
					(size 1.27 1.27)
					(thickness 0.15)
				)
			)
		)
		(property "Author" "Antmicro"
			(at -61.5445 161.1045 0)
			(layer "B.Fab")
			(hide yes)
			(effects
				(font
					(size 1 1)
					(thickness 0.15)
				)
				(justify mirror)
			)
		)
		(property "License" "Apache-2.0"
			(at -61.5445 161.1045 0)
			(layer "B.Fab")
			(hide yes)
			(effects
				(font
					(size 1 1)
					(thickness 0.15)
				)
				(justify mirror)
			)
		)
		(property "MPN" "NTS0102GT"
			(at -61.5445 161.1045 0)
			(layer "B.Fab")
			(hide yes)
			(effects
				(font
					(size 1 1)
					(thickness 0.15)
				)
				(justify mirror)
			)
		)
		(property "Manufacturer" "NXP"
			(at -61.5445 161.1045 0)
			(layer "B.Fab")
			(hide yes)
			(effects
				(font
					(size 1 1)
					(thickness 0.15)
				)
				(justify mirror)
			)
		)
		(sheetname "USB Debug, DP")
		(sheetfile "usb.kicad_sch")
		(attr smd)
		(fp_line
			(start 0.5 1.1)
			(end -0.5 1.1)
			(stroke
				(width 0.15)
				(type solid)
			)
			(layer "B.SilkS")
		)
		(fp_line
			(start -0.5 -1.1)
			(end 0.5 -1.1)
			(stroke
				(width 0.15)
				(type solid)
			)
			(layer "B.SilkS")
		)
		(fp_circle
			(center -0.75 1.1)
			(end -0.701 1.1)
			(stroke
				(width 0.15)
				(type solid)
			)
			(fill none)
			(layer "B.SilkS")
		)
		(fp_rect
			(start -0.8 1.2)
			(end 0.8 -1.2)
			(stroke
				(width 0.05)
				(type solid)
			)
			(fill none)
			(layer "B.CrtYd")
		)
		(fp_line
			(start -0.5305 1.001)
			(end -0.5305 -1)
			(stroke
				(width 0.15)
				(type solid)
			)
			(layer "B.Fab")
		)
		(fp_line
			(start 0.5305 1.001)
			(end -0.5305 1.001)
			(stroke
				(width 0.15)
				(type solid)
			)
			(layer "B.Fab")
		)
		(fp_line
			(start -0.5305 -1)
			(end 0.5305 -1)
			(stroke
				(width 0.15)
				(type solid)
			)
			(layer "B.Fab")
		)
		(fp_line
			(start 0.5305 -1)
			(end 0.5305 1.001)
			(stroke
				(width 0.15)
				(type solid)
			)
			(layer "B.Fab")
		)
		(fp_text user "${REFERENCE}"
			(at -0.527 -5.905 90)
			(layer "B.Fab")
			(hide yes)
			(effects
				(font
					(size 0.7 0.7)
					(thickness 0.15)
				)
				(justify left bottom mirror)
			)
		)
		(fp_text user "Author: Antmicro"
			(at -0.527 -7.105 90)
			(layer "B.Fab")
			(hide yes)
			(effects
				(font
					(size 0.7 0.7)
					(thickness 0.15)
				)
				(justify left bottom mirror)
			)
		)
		(fp_text user "License: Apache-2.0"
			(at -0.527 -8.306 90)
			(layer "B.Fab")
			(hide yes)
			(effects
				(font
					(size 0.7 0.7)
					(thickness 0.15)
				)
				(justify left bottom mirror)
			)
		)
		(pad "1" smd roundrect
			(at -0.45 0.75 90)
			(size 0.6 0.3)
			(layers "B.Cu" "B.Paste" "B.Mask")
			(roundrect_rratio 0.25)
			(net 302 "/USB Debug, DP/PDC_I2C1_SCL")
			(pinfunction "B_{2}")
			(pintype "bidirectional")
		)
		(pad "2" smd roundrect
			(at -0.45 0.25 90)
			(size 0.6 0.25)
			(layers "B.Cu" "B.Paste" "B.Mask")
			(roundrect_rratio 0.25)
			(net 1 "GND")
			(pinfunction "GND")
			(pintype "power_in")
		)
		(pad "3" smd roundrect
			(at -0.45 -0.25 90)
			(size 0.6 0.25)
			(layers "B.Cu" "B.Paste" "B.Mask")
			(roundrect_rratio 0.25)
			(net 185 "/USB Debug, DP/FTDI_3V3")
			(pinfunction "VCC_{A}")
			(pintype "power_in")
		)
		(pad "4" smd roundrect
			(at -0.45 -0.75 90)
			(size 0.6 0.3)
			(layers "B.Cu" "B.Paste" "B.Mask")
			(roundrect_rratio 0.25)
			(net 398 "/USB Debug, DP/FTDI_CBUS3{slash}SCL")
			(pinfunction "A_{2}")
			(pintype "bidirectional")
		)
		(pad "5" smd roundrect
			(at 0.45 -0.75 90)
			(size 0.6 0.3)
			(layers "B.Cu" "B.Paste" "B.Mask")
			(roundrect_rratio 0.25)
			(net 780 "/USB Debug, DP/FTDI_CBUS0{slash}SDA")
			(pinfunction "A_{1}")
			(pintype "bidirectional")
		)
		(pad "6" smd roundrect
			(at 0.45 -0.25 90)
			(size 0.6 0.25)
			(layers "B.Cu" "B.Paste" "B.Mask")
			(roundrect_rratio 0.25)
			(net 397 "/USB Debug, DP/FTDI_CBUS_EN")
			(pinfunction "OE")
			(pintype "input")
		)
		(pad "7" smd roundrect
			(at 0.45 0.25 90)
			(size 0.6 0.25)
			(layers "B.Cu" "B.Paste" "B.Mask")
			(roundrect_rratio 0.25)
			(net 185 "/USB Debug, DP/FTDI_3V3")
			(pinfunction "VCC_{B}")
			(pintype "power_in")
		)
		(pad "8" smd roundrect
			(at 0.45 0.75 90)
			(size 0.6 0.3)
			(layers "B.Cu" "B.Paste" "B.Mask")
			(roundrect_rratio 0.25)
			(net 303 "/USB Debug, DP/PDC_I2C1_SDA")
			(pinfunction "B_{1}")
			(pintype "bidirectional")
		)
	)
	(footprint "antmicro-footprints:R_0402_1005Metric"
		(layer "B.Cu")
		(at 92.9 98.5 -90)
		(descr "Resistor SMD 0402")
		(tags "resistor SMD 0402")
		(property "Reference" "R211"
			(at -1.57 0.35 90)
			(layer "B.SilkS")
			(effects
				(font
					(size 0.7 0.7)
					(thickness 0.15)
				)
				(justify left bottom mirror)
			)
		)
		(property "Value" "R_10k_0402"
			(at 0 -1.4 90)
			(layer "B.Fab")
			(effects
				(font
					(size 0.7 0.7)
					(thickness 0.15)
				)
				(justify left bottom mirror)
			)
		)
		(property "Footprint" "antmicro-footprints:R_0402_1005Metric"
			(at 0 0 -90)
			(layer "F.Fab")
			(hide yes)
			(effects
				(font
					(size 1.27 1.27)
					(thickness 0.15)
				)
			)
		)
		(property "Datasheet" "https://www.bourns.com/docs/product-datasheets/cr.pdf"
			(at 0 0 -90)
			(layer "F.Fab")
			(hide yes)
			(effects
				(font
					(size 1.27 1.27)
					(thickness 0.15)
				)
			)
		)
		(property "Author" "Antmicro"
			(at -5.6 191.4 0)
			(layer "B.Fab")
			(hide yes)
			(effects
				(font
					(size 1 1)
					(thickness 0.15)
				)
				(justify mirror)
			)
		)
		(property "License" "Apache-2.0"
			(at -5.6 191.4 0)
			(layer "B.Fab")
			(hide yes)
			(effects
				(font
					(size 1 1)
					(thickness 0.15)
				)
				(justify mirror)
			)
		)
		(property "MPN" "CR0402-FX-1002GLF"
			(at -5.6 191.4 0)
			(layer "B.Fab")
			(hide yes)
			(effects
				(font
					(size 1 1)
					(thickness 0.15)
				)
				(justify mirror)
			)
		)
		(property "Manufacturer" "Bourns"
			(at -5.6 191.4 0)
			(layer "B.Fab")
			(hide yes)
			(effects
				(font
					(size 1 1)
					(thickness 0.15)
				)
				(justify mirror)
			)
		)
		(property "Tolerance" "1%"
			(at -5.6 191.4 0)
			(layer "B.Fab")
			(hide yes)
			(effects
				(font
					(size 1 1)
					(thickness 0.15)
				)
				(justify mirror)
			)
		)
		(property "Val" "10k"
			(at -5.6 191.4 0)
			(layer "B.Fab")
			(hide yes)
			(effects
				(font
					(size 1 1)
					(thickness 0.15)
				)
				(justify mirror)
			)
		)
		(sheetname "HDMI")
		(sheetfile "hdmi.kicad_sch")
		(attr smd)
		(fp_rect
			(start -0.925 0.47)
			(end 0.925 -0.47)
			(stroke
				(width 0.05)
				(type default)
			)
			(fill none)
			(layer "B.CrtYd")
		)
		(fp_rect
			(start -0.5 0.25)
			(end 0.5 -0.25)
			(stroke
				(width 0.15)
				(type solid)
			)
			(fill none)
			(layer "B.Fab")
		)
		(fp_text user "License: Apache-2.0"
			(at -0.95 -5.169 90)
			(layer "B.Fab")
			(hide yes)
			(effects
				(font
					(size 0.7 0.7)
					(thickness 0.15)
				)
				(justify left bottom mirror)
			)
		)
		(fp_text user "${REFERENCE}"
			(at -0.95 -3.168 90)
			(layer "B.Fab")
			(hide yes)
			(effects
				(font
					(size 0.7 0.7)
					(thickness 0.15)
				)
				(justify left bottom mirror)
			)
		)
		(fp_text user "Author: Antmicro"
			(at -0.95 -4.169 90)
			(layer "B.Fab")
			(hide yes)
			(effects
				(font
					(size 0.7 0.7)
					(thickness 0.15)
				)
				(justify left bottom mirror)
			)
		)
		(pad "1" smd roundrect
			(at -0.48 0 270)
			(size 0.59 0.64)
			(layers "B.Cu" "B.Paste" "B.Mask")
			(roundrect_rratio 0.25)
			(net 686 "Net-(U36-SEL1)")
			(pintype "passive")
		)
		(pad "2" smd roundrect
			(at 0.48 0 270)
			(size 0.59 0.64)
			(layers "B.Cu" "B.Paste" "B.Mask")
			(roundrect_rratio 0.25)
			(net 87 "+3V3")
			(pintype "passive")
		)
	)
)
